(kicad_pcb
	(version 20260206)
	(generator "pcbnew")
	(generator_version "10.0")
	(general
		(thickness 1.6)
		(legacy_teardrops no)
	)
	(paper "A4")
	(title_block
		(title "baseboard — 13948-1b.1110WZS1818.brd")
		(comment 1 "Honey Badger (Wiwynn) / footprints 603-609 of 2523")
	)
	(layers
		(0 "F.Cu" signal "TOP")
		(4 "In1.Cu" signal "L2GND")
		(6 "In2.Cu" signal "L3")
		(8 "In3.Cu" signal "L4VCC")
		(10 "In4.Cu" signal "L5VCC")
		(12 "In5.Cu" signal "L6")
		(14 "In6.Cu" signal "L7GND")
		(2 "B.Cu" signal "BOTTOM")
		(9 "F.Adhes" user "F.Adhesive")
		(11 "B.Adhes" user "B.Adhesive")
		(13 "F.Paste" user "Package Geometry/Pastemask Top")
		(15 "B.Paste" user "Package Geometry/Pastemask Bottom")
		(5 "F.SilkS" user "Ref Des/Silkscreen Top")
		(7 "B.SilkS" user "Ref Des/Silkscreen Bottom")
		(1 "F.Mask" user "Board Geometry/Soldermask Top")
		(3 "B.Mask" user "Board Geometry/Soldermask Bottom")
		(17 "Dwgs.User" user "User.Drawings")
		(19 "Cmts.User" user "User.Comments")
		(21 "Eco1.User" user "User.Eco1")
		(23 "Eco2.User" user "User.Eco2")
		(25 "Edge.Cuts" user "Board Geometry/Outline")
		(27 "Margin" user)
		(31 "F.CrtYd" user "Package Geometry/Place Bound Top")
		(29 "B.CrtYd" user "Package Geometry/Place Bound Bottom")
		(35 "F.Fab" user "Ref Des/Assembly Top")
		(33 "B.Fab" user "Ref Des/Assembly Bottom")
	)
	(footprint ""
		(layer "F.Cu")
		(at 266.446 -236.22 -90)
		(property "Reference" "C86"
			(at 0 0 270)
			(layer "F.SilkS")
			(hide yes)
			(effects
				(font
					(size 1.27 1.27)
				)
			)
		)
		(property "Value" "SCD1U16V2KX-3GP"
			(at 1.1811 -2.7051 270)
			(unlocked yes)
			(layer "F.Fab")
			(hide yes)
			(effects
				(font
					(size 1.016 1.016)
					(thickness 0.1524)
				)
			)
		)
		(property "Device Type" "C402H22"
			(at 1.1811 -4.2291 270)
			(unlocked yes)
			(layer "F.Fab")
			(hide yes)
			(effects
				(font
					(size 1.016 1.016)
					(thickness 0.1524)
				)
			)
		)
		(duplicate_pad_numbers_are_jumpers no)
		(fp_rect
			(start -0.4318 0.9525)
			(end 0.4318 -0.9525)
			(stroke
				(width 0)
				(type default)
			)
			(fill no)
			(layer "F.CrtYd")
		)
		(fp_rect
			(start -0.4318 0.9525)
			(end 0.4318 -0.9525)
			(stroke
				(width 0)
				(type default)
			)
			(fill no)
			(layer "F.Fab")
		)
		(pad "1" smd custom
			(at 0 -0.4445 270)
			(size 0.1524 0.1524)
			(layers "F.Cu" "F.Mask" "F.Paste")
			(net "P1V8_STBY")
			(options
				(clearance outline)
				(anchor circle)
			)
			(primitives
				(gr_poly
					(pts
						(arc
							(start 0.3048 -0.2032)
							(mid 0.275042 -0.275042)
							(end 0.2032 -0.3048)
						)
						(arc
							(start -0.2032 -0.3048)
							(mid -0.275042 -0.275042)
							(end -0.3048 -0.2032)
						)
						(arc
							(start -0.3048 0.2032)
							(mid -0.275042 0.275042)
							(end -0.2032 0.3048)
						)
						(arc
							(start 0.2032 0.3048)
							(mid 0.275042 0.275042)
							(end 0.3048 0.2032)
						)
					)
					(width 0)
					(fill yes)
				)
			)
		)
		(pad "2" smd custom
			(at 0 0.4445 270)
			(size 0.1524 0.1524)
			(layers "F.Cu" "F.Mask" "F.Paste")
			(net "GND")
			(options
				(clearance outline)
				(anchor circle)
			)
			(primitives
				(gr_poly
					(pts
						(arc
							(start 0.3048 -0.2032)
							(mid 0.275042 -0.275042)
							(end 0.2032 -0.3048)
						)
						(arc
							(start -0.2032 -0.3048)
							(mid -0.275042 -0.275042)
							(end -0.3048 -0.2032)
						)
						(arc
							(start -0.3048 0.2032)
							(mid -0.275042 0.275042)
							(end -0.2032 0.3048)
						)
						(arc
							(start 0.2032 0.3048)
							(mid 0.275042 0.275042)
							(end 0.3048 0.2032)
						)
					)
					(width 0)
					(fill yes)
				)
			)
		)
	)
	(footprint ""
		(layer "F.Cu")
		(at 107.88777 -69.9008 -90)
		(property "Reference" "R585"
			(at 0 0 270)
			(layer "F.SilkS")
			(hide yes)
			(effects
				(font
					(size 1.27 1.27)
				)
			)
		)
		(property "Value" "4K7R2F-GP"
			(at 0.064008 -3.993896 270)
			(unlocked yes)
			(layer "F.Fab")
			(hide yes)
			(effects
				(font
					(size 1.016 1.016)
					(thickness 0.1524)
				)
			)
		)
		(property "Device Type" "R402H16"
			(at 0.064008 -5.517896 270)
			(unlocked yes)
			(layer "F.Fab")
			(hide yes)
			(effects
				(font
					(size 1.016 1.016)
					(thickness 0.1524)
				)
			)
		)
		(duplicate_pad_numbers_are_jumpers no)
		(fp_line
			(start -0.508 -0.9398)
			(end -0.508 0.9398)
			(stroke
				(width 0.1524)
				(type default)
			)
			(layer "F.SilkS")
		)
		(fp_line
			(start 0.508 -0.9398)
			(end -0.508 -0.9398)
			(stroke
				(width 0.1524)
				(type default)
			)
			(layer "F.SilkS")
		)
		(fp_rect
			(start -0.508 0.9398)
			(end 0.508 -0.9398)
			(stroke
				(width 0)
				(type default)
			)
			(fill no)
			(layer "F.CrtYd")
		)
		(fp_rect
			(start -0.508 0.9398)
			(end 0.508 -0.9398)
			(stroke
				(width 0)
				(type default)
			)
			(fill no)
			(layer "F.Fab")
		)
		(pad "1" smd custom
			(at 0 -0.4445 270)
			(size 0.1397 0.1397)
			(layers "F.Cu" "F.Mask" "F.Paste")
			(net "TEMP_4_A0")
			(options
				(clearance outline)
				(anchor circle)
			)
			(primitives
				(gr_poly
					(pts
						(arc
							(start -0.1778 -0.2794)
							(mid -0.249642 -0.249642)
							(end -0.2794 -0.1778)
						)
						(arc
							(start -0.2794 0.1778)
							(mid -0.249642 0.249642)
							(end -0.1778 0.2794)
						)
						(arc
							(start 0.1778 0.2794)
							(mid 0.249642 0.249642)
							(end 0.2794 0.1778)
						)
						(arc
							(start 0.2794 -0.1778)
							(mid 0.249642 -0.249642)
							(end 0.1778 -0.2794)
						)
					)
					(width 0)
					(fill yes)
				)
			)
		)
		(pad "2" smd custom
			(at 0 0.4445 270)
			(size 0.1397 0.1397)
			(layers "F.Cu" "F.Mask" "F.Paste")
			(net "GND")
			(options
				(clearance outline)
				(anchor circle)
			)
			(primitives
				(gr_poly
					(pts
						(arc
							(start -0.1778 -0.2794)
							(mid -0.249642 -0.249642)
							(end -0.2794 -0.1778)
						)
						(arc
							(start -0.2794 0.1778)
							(mid -0.249642 0.249642)
							(end -0.1778 0.2794)
						)
						(arc
							(start 0.1778 0.2794)
							(mid 0.249642 0.249642)
							(end 0.2794 0.1778)
						)
						(arc
							(start 0.2794 -0.1778)
							(mid 0.249642 -0.249642)
							(end 0.1778 -0.2794)
						)
					)
					(width 0)
					(fill yes)
				)
			)
		)
	)
	(footprint ""
		(layer "F.Cu")
		(at 277.994872 -219.274136 -90)
		(property "Reference" "PC88"
			(at 0 0 270)
			(layer "F.SilkS")
			(hide yes)
			(effects
				(font
					(size 1.27 1.27)
				)
			)
		)
		(property "Value" "SCD1U16V2KX-3GP"
			(at 1.1811 -2.7051 270)
			(unlocked yes)
			(layer "F.Fab")
			(hide yes)
			(effects
				(font
					(size 1.016 1.016)
					(thickness 0.1524)
				)
			)
		)
		(property "Device Type" "C402H22"
			(at 1.1811 -4.2291 270)
			(unlocked yes)
			(layer "F.Fab")
			(hide yes)
			(effects
				(font
					(size 1.016 1.016)
					(thickness 0.1524)
				)
			)
		)
		(duplicate_pad_numbers_are_jumpers no)
		(fp_rect
			(start -0.4318 0.9525)
			(end 0.4318 -0.9525)
			(stroke
				(width 0)
				(type default)
			)
			(fill no)
			(layer "F.CrtYd")
		)
		(fp_rect
			(start -0.4318 0.9525)
			(end 0.4318 -0.9525)
			(stroke
				(width 0)
				(type default)
			)
			(fill no)
			(layer "F.Fab")
		)
		(pad "1" smd custom
			(at 0 -0.4445 270)
			(size 0.1524 0.1524)
			(layers "F.Cu" "F.Mask" "F.Paste")
			(net "TPS74801_1V53_STBY_BIAS")
			(options
				(clearance outline)
				(anchor circle)
			)
			(primitives
				(gr_poly
					(pts
						(arc
							(start 0.3048 -0.2032)
							(mid 0.275042 -0.275042)
							(end 0.2032 -0.3048)
						)
						(arc
							(start -0.2032 -0.3048)
							(mid -0.275042 -0.275042)
							(end -0.3048 -0.2032)
						)
						(arc
							(start -0.3048 0.2032)
							(mid -0.275042 0.275042)
							(end -0.2032 0.3048)
						)
						(arc
							(start 0.2032 0.3048)
							(mid 0.275042 0.275042)
							(end 0.3048 0.2032)
						)
					)
					(width 0)
					(fill yes)
				)
			)
		)
		(pad "2" smd custom
			(at 0 0.4445 270)
			(size 0.1524 0.1524)
			(layers "F.Cu" "F.Mask" "F.Paste")
			(net "GND")
			(options
				(clearance outline)
				(anchor circle)
			)
			(primitives
				(gr_poly
					(pts
						(arc
							(start 0.3048 -0.2032)
							(mid 0.275042 -0.275042)
							(end 0.2032 -0.3048)
						)
						(arc
							(start -0.2032 -0.3048)
							(mid -0.275042 -0.275042)
							(end -0.3048 -0.2032)
						)
						(arc
							(start -0.3048 0.2032)
							(mid -0.275042 0.275042)
							(end -0.2032 0.3048)
						)
						(arc
							(start 0.2032 0.3048)
							(mid 0.275042 0.275042)
							(end 0.3048 0.2032)
						)
					)
					(width 0)
					(fill yes)
				)
			)
		)
	)
	(footprint ""
		(layer "F.Cu")
		(at 291.973 -207.772 90)
		(property "Reference" "R232"
			(at 0 0 90)
			(layer "F.SilkS")
			(hide yes)
			(effects
				(font
					(size 1.27 1.27)
				)
			)
		)
		(property "Value" "1KR2F-3-GP"
			(at 0.064008 -3.993896 90)
			(unlocked yes)
			(layer "F.Fab")
			(hide yes)
			(effects
				(font
					(size 1.016 1.016)
					(thickness 0.1524)
				)
			)
		)
		(property "Device Type" "R402H16"
			(at 0.064008 -5.517896 90)
			(unlocked yes)
			(layer "F.Fab")
			(hide yes)
			(effects
				(font
					(size 1.016 1.016)
					(thickness 0.1524)
				)
			)
		)
		(duplicate_pad_numbers_are_jumpers no)
		(fp_line
			(start 0.508 -0.9398)
			(end -0.508 -0.9398)
			(stroke
				(width 0.1524)
				(type default)
			)
			(layer "F.SilkS")
		)
		(fp_line
			(start -0.508 -0.9398)
			(end -0.508 0.9398)
			(stroke
				(width 0.1524)
				(type default)
			)
			(layer "F.SilkS")
		)
		(fp_rect
			(start -0.508 0.9398)
			(end 0.508 -0.9398)
			(stroke
				(width 0)
				(type default)
			)
			(fill no)
			(layer "F.CrtYd")
		)
		(fp_rect
			(start -0.508 0.9398)
			(end 0.508 -0.9398)
			(stroke
				(width 0)
				(type default)
			)
			(fill no)
			(layer "F.Fab")
		)
		(pad "1" smd custom
			(at 0 -0.4445 90)
			(size 0.1397 0.1397)
			(layers "F.Cu" "F.Mask" "F.Paste")
			(net "DDR_VREF")
			(options
				(clearance outline)
				(anchor circle)
			)
			(primitives
				(gr_poly
					(pts
						(arc
							(start -0.1778 -0.2794)
							(mid -0.249642 -0.249642)
							(end -0.2794 -0.1778)
						)
						(arc
							(start -0.2794 0.1778)
							(mid -0.249642 0.249642)
							(end -0.1778 0.2794)
						)
						(arc
							(start 0.1778 0.2794)
							(mid 0.249642 0.249642)
							(end 0.2794 0.1778)
						)
						(arc
							(start 0.2794 -0.1778)
							(mid 0.249642 -0.249642)
							(end 0.1778 -0.2794)
						)
					)
					(width 0)
					(fill yes)
				)
			)
		)
		(pad "2" smd custom
			(at 0 0.4445 90)
			(size 0.1397 0.1397)
			(layers "F.Cu" "F.Mask" "F.Paste")
			(net "GND")
			(options
				(clearance outline)
				(anchor circle)
			)
			(primitives
				(gr_poly
					(pts
						(arc
							(start -0.1778 -0.2794)
							(mid -0.249642 -0.249642)
							(end -0.2794 -0.1778)
						)
						(arc
							(start -0.2794 0.1778)
							(mid -0.249642 0.249642)
							(end -0.1778 0.2794)
						)
						(arc
							(start 0.1778 0.2794)
							(mid 0.249642 0.249642)
							(end 0.2794 0.1778)
						)
						(arc
							(start 0.2794 -0.1778)
							(mid 0.249642 -0.249642)
							(end 0.1778 -0.2794)
						)
					)
					(width 0)
					(fill yes)
				)
			)
		)
	)
	(footprint ""
		(layer "F.Cu")
		(at 11.126216 -211.63788 -90)
		(property "Reference" "Q92"
			(at 0 0 270)
			(layer "F.SilkS")
			(hide yes)
			(effects
				(font
					(size 1.27 1.27)
				)
			)
		)
		(property "Value" "2N7002A-7-GP"
			(at 0.127 -8.9662 270)
			(unlocked yes)
			(layer "F.Fab")
			(hide yes)
			(effects
				(font
					(size 1.016 1.016)
					(thickness 0.1524)
				)
			)
		)
		(property "Device Type" "SOT23DGS2D4H48"
			(at 0.127 -10.4902 270)
			(unlocked yes)
			(layer "F.Fab")
			(hide yes)
			(effects
				(font
					(size 1.016 1.016)
					(thickness 0.1524)
				)
			)
		)
		(duplicate_pad_numbers_are_jumpers no)
		(fp_line
			(start -1.651 1.778)
			(end 1.651 1.778)
			(stroke
				(width 0.1524)
				(type default)
			)
			(layer "F.SilkS")
		)
		(fp_line
			(start 1.651 1.778)
			(end 1.651 -1.778)
			(stroke
				(width 0.1524)
				(type default)
			)
			(layer "F.SilkS")
		)
		(fp_line
			(start -1.651 -1.778)
			(end -1.651 1.778)
			(stroke
				(width 0.1524)
				(type default)
			)
			(layer "F.SilkS")
		)
		(fp_line
			(start 1.651 -1.778)
			(end -1.651 -1.778)
			(stroke
				(width 0.1524)
				(type default)
			)
			(layer "F.SilkS")
		)
		(fp_poly
			(pts
				(xy -1.778 1.8796) (xy -1.778 -1.8796) (xy 1.778 -1.8796) (xy 1.778 1.8796)
			)
			(stroke
				(width 0)
				(type default)
			)
			(fill no)
			(layer "F.CrtYd")
		)
		(fp_poly
			(pts
				(xy -1.778 1.8796) (xy -1.778 -1.8796) (xy 1.778 -1.8796) (xy 1.778 1.8796)
			)
			(stroke
				(width 0)
				(type default)
			)
			(fill no)
			(layer "F.Fab")
		)
		(pad "D" smd custom
			(at 0 -0.9525 270)
			(size 0.1905 0.1905)
			(layers "F.Cu" "F.Mask" "F.Paste")
			(net "PCIE_MATED#")
			(options
				(clearance outline)
				(anchor circle)
			)
			(primitives
				(gr_poly
					(pts
						(arc
							(start -0.1778 0.5715)
							(mid -0.321484 0.511984)
							(end -0.381 0.3683)
						)
						(arc
							(start -0.381 -0.3683)
							(mid -0.321484 -0.511984)
							(end -0.1778 -0.5715)
						)
						(arc
							(start 0.1778 -0.5715)
							(mid 0.321484 -0.511984)
							(end 0.381 -0.3683)
						)
						(arc
							(start 0.381 0.3683)
							(mid 0.321484 0.511984)
							(end 0.1778 0.5715)
						)
					)
					(width 0)
					(fill yes)
				)
			)
		)
		(pad "G" smd custom
			(at -0.98425 0.9525 270)
			(size 0.1905 0.1905)
			(layers "F.Cu" "F.Mask" "F.Paste")
			(net "MATED#")
			(options
				(clearance outline)
				(anchor circle)
			)
			(primitives
				(gr_poly
					(pts
						(arc
							(start -0.1778 0.5715)
							(mid -0.321484 0.511984)
							(end -0.381 0.3683)
						)
						(arc
							(start -0.381 -0.3683)
							(mid -0.321484 -0.511984)
							(end -0.1778 -0.5715)
						)
						(arc
							(start 0.1778 -0.5715)
							(mid 0.321484 -0.511984)
							(end 0.381 -0.3683)
						)
						(arc
							(start 0.381 0.3683)
							(mid 0.321484 0.511984)
							(end 0.1778 0.5715)
						)
					)
					(width 0)
					(fill yes)
				)
			)
		)
		(pad "S" smd custom
			(at 0.98425 0.9525 270)
			(size 0.1905 0.1905)
			(layers "F.Cu" "F.Mask" "F.Paste")
			(net "GND")
			(options
				(clearance outline)
				(anchor circle)
			)
			(primitives
				(gr_poly
					(pts
						(arc
							(start -0.1778 0.5715)
							(mid -0.321484 0.511984)
							(end -0.381 0.3683)
						)
						(arc
							(start -0.381 -0.3683)
							(mid -0.321484 -0.511984)
							(end -0.1778 -0.5715)
						)
						(arc
							(start 0.1778 -0.5715)
							(mid 0.321484 -0.511984)
							(end 0.381 -0.3683)
						)
						(arc
							(start 0.381 0.3683)
							(mid 0.321484 0.511984)
							(end 0.1778 0.5715)
						)
					)
					(width 0)
					(fill yes)
				)
			)
		)
	)
	(footprint ""
		(layer "F.Cu")
		(at 308.60238 -144.40154 -90)
		(property "Reference" "R7789"
			(at 0 0 270)
			(layer "F.SilkS")
			(hide yes)
			(effects
				(font
					(size 1.27 1.27)
				)
			)
		)
		(property "Value" "49D9R2F-GP"
			(at 0.064008 -3.993896 270)
			(unlocked yes)
			(layer "F.Fab")
			(hide yes)
			(effects
				(font
					(size 1.016 1.016)
					(thickness 0.1524)
				)
			)
		)
		(property "Device Type" "R402H16"
			(at 0.064008 -5.517896 270)
			(unlocked yes)
			(layer "F.Fab")
			(hide yes)
			(effects
				(font
					(size 1.016 1.016)
					(thickness 0.1524)
				)
			)
		)
		(duplicate_pad_numbers_are_jumpers no)
		(fp_line
			(start -0.508 -0.9398)
			(end -0.508 0.9398)
			(stroke
				(width 0.1524)
				(type default)
			)
			(layer "F.SilkS")
		)
		(fp_line
			(start 0.508 -0.9398)
			(end -0.508 -0.9398)
			(stroke
				(width 0.1524)
				(type default)
			)
			(layer "F.SilkS")
		)
		(fp_rect
			(start -0.508 0.9398)
			(end 0.508 -0.9398)
			(stroke
				(width 0)
				(type default)
			)
			(fill no)
			(layer "F.CrtYd")
		)
		(fp_rect
			(start -0.508 0.9398)
			(end 0.508 -0.9398)
			(stroke
				(width 0)
				(type default)
			)
			(fill no)
			(layer "F.Fab")
		)
		(pad "1" smd custom
			(at 0 -0.4445 270)
			(size 0.1397 0.1397)
			(layers "F.Cu" "F.Mask" "F.Paste")
			(net "OSC_OE")
			(options
				(clearance outline)
				(anchor circle)
			)
			(primitives
				(gr_poly
					(pts
						(arc
							(start -0.1778 -0.2794)
							(mid -0.249642 -0.249642)
							(end -0.2794 -0.1778)
						)
						(arc
							(start -0.2794 0.1778)
							(mid -0.249642 0.249642)
							(end -0.1778 0.2794)
						)
						(arc
							(start 0.1778 0.2794)
							(mid 0.249642 0.249642)
							(end 0.2794 0.1778)
						)
						(arc
							(start 0.2794 -0.1778)
							(mid 0.249642 -0.249642)
							(end 0.1778 -0.2794)
						)
					)
					(width 0)
					(fill yes)
				)
			)
		)
		(pad "2" smd custom
			(at 0 0.4445 270)
			(size 0.1397 0.1397)
			(layers "F.Cu" "F.Mask" "F.Paste")
			(net "P3V3_STBY")
			(options
				(clearance outline)
				(anchor circle)
			)
			(primitives
				(gr_poly
					(pts
						(arc
							(start -0.1778 -0.2794)
							(mid -0.249642 -0.249642)
							(end -0.2794 -0.1778)
						)
						(arc
							(start -0.2794 0.1778)
							(mid -0.249642 0.249642)
							(end -0.1778 0.2794)
						)
						(arc
							(start 0.1778 0.2794)
							(mid 0.249642 0.249642)
							(end 0.2794 0.1778)
						)
						(arc
							(start 0.2794 -0.1778)
							(mid 0.249642 -0.249642)
							(end 0.1778 -0.2794)
						)
					)
					(width 0)
					(fill yes)
				)
			)
		)
	)
	(footprint ""
		(layer "F.Cu")
		(at 270.637 -16.764 180)
		(property "Reference" "C238"
			(at 0 0 180)
			(layer "F.SilkS")
			(hide yes)
			(effects
				(font
					(size 1.27 1.27)
				)
			)
		)
		(property "Value" "SCD1U16V2JX-1-GP"
			(at 1.1811 -2.7051 180)
			(unlocked yes)
			(layer "F.Fab")
			(hide yes)
			(effects
				(font
					(size 1.016 1.016)
					(thickness 0.1524)
				)
			)
		)
		(property "Device Type" "C402H22"
			(at 1.1811 -4.2291 180)
			(unlocked yes)
			(layer "F.Fab")
			(hide yes)
			(effects
				(font
					(size 1.016 1.016)
					(thickness 0.1524)
				)
			)
		)
		(duplicate_pad_numbers_are_jumpers no)
		(fp_rect
			(start -0.4318 0.9525)
			(end 0.4318 -0.9525)
			(stroke
				(width 0)
				(type default)
			)
			(fill no)
			(layer "F.CrtYd")
		)
		(fp_rect
			(start -0.4318 0.9525)
			(end 0.4318 -0.9525)
			(stroke
				(width 0)
				(type default)
			)
			(fill no)
			(layer "F.Fab")
		)
		(pad "1" smd custom
			(at 0 -0.4445 180)
			(size 0.1524 0.1524)
			(layers "F.Cu" "F.Mask" "F.Paste")
			(net "P5V_USB")
			(options
				(clearance outline)
				(anchor circle)
			)
			(primitives
				(gr_poly
					(pts
						(arc
							(start 0.3048 -0.2032)
							(mid 0.275042 -0.275042)
							(end 0.2032 -0.3048)
						)
						(arc
							(start -0.2032 -0.3048)
							(mid -0.275042 -0.275042)
							(end -0.3048 -0.2032)
						)
						(arc
							(start -0.3048 0.2032)
							(mid -0.275042 0.275042)
							(end -0.2032 0.3048)
						)
						(arc
							(start 0.2032 0.3048)
							(mid 0.275042 0.275042)
							(end 0.3048 0.2032)
						)
					)
					(width 0)
					(fill yes)
				)
			)
		)
		(pad "2" smd custom
			(at 0 0.4445 180)
			(size 0.1524 0.1524)
			(layers "F.Cu" "F.Mask" "F.Paste")
			(net "GND")
			(options
				(clearance outline)
				(anchor circle)
			)
			(primitives
				(gr_poly
					(pts
						(arc
							(start 0.3048 -0.2032)
							(mid 0.275042 -0.275042)
							(end 0.2032 -0.3048)
						)
						(arc
							(start -0.2032 -0.3048)
							(mid -0.275042 -0.275042)
							(end -0.3048 -0.2032)
						)
						(arc
							(start -0.3048 0.2032)
							(mid -0.275042 0.275042)
							(end -0.2032 0.3048)
						)
						(arc
							(start 0.2032 0.3048)
							(mid 0.275042 0.275042)
							(end 0.3048 0.2032)
						)
					)
					(width 0)
					(fill yes)
				)
			)
		)
	)
)
